(kicad_pcb
	(version 20260206)
	(generator "pcbnew")
	(generator_version "10.0")
	(general
		(thickness 1.6)
		(legacy_teardrops no)
	)
	(paper "A4")
	(title_block
		(title "01162023_DA0F0TEBIF0_F0T_Expander_BD_F_brd_V02_OCP.brd")
		(comment 1 "Grand Teton / footprints 8317-8323 of 9728")
	)
	(layers
		(0 "F.Cu" signal "TOP")
		(4 "In1.Cu" signal "GND")
		(6 "In2.Cu" signal "VCC")
		(8 "In3.Cu" signal "VCC1")
		(10 "In4.Cu" signal "GND1")
		(12 "In5.Cu" signal "IN1")
		(14 "In6.Cu" signal "GND2")
		(16 "In7.Cu" signal "IN2")
		(18 "In8.Cu" signal "GND3")
		(20 "In9.Cu" signal "IN3")
		(22 "In10.Cu" signal "GND4")
		(24 "In11.Cu" signal "IN4")
		(26 "In12.Cu" signal "GND5")
		(28 "In13.Cu" signal "IN5")
		(30 "In14.Cu" signal "GND6")
		(32 "In15.Cu" signal "IN6")
		(34 "In16.Cu" signal "GND7")
		(2 "B.Cu" signal "BOTTOM")
		(9 "F.Adhes" user "F.Adhesive")
		(11 "B.Adhes" user "B.Adhesive")
		(13 "F.Paste" user "Package Geometry/Pastemask Top")
		(15 "B.Paste" user "Package Geometry/Pastemask Bottom")
		(5 "F.SilkS" user "Ref Des/Silkscreen Top")
		(7 "B.SilkS" user "Ref Des/Silkscreen Bottom")
		(1 "F.Mask" user "Board Geometry/Soldermask Top")
		(3 "B.Mask" user "Board Geometry/Soldermask Bottom")
		(17 "Dwgs.User" user "User.Drawings")
		(19 "Cmts.User" user "User.Comments")
		(21 "Eco1.User" user "User.Eco1")
		(23 "Eco2.User" user "User.Eco2")
		(25 "Edge.Cuts" user "Board Geometry/Outline")
		(27 "Margin" user)
		(31 "F.CrtYd" user "Package Geometry/Place Bound Top")
		(29 "B.CrtYd" user "Package Geometry/Place Bound Bottom")
		(35 "F.Fab" user "Ref Des/Assembly Top")
		(33 "B.Fab" user "Ref Des/Assembly Bottom")
	)
	(footprint ""
		(layer "B.Cu")
		(at 449.857876 -274.541996)
		(property "Reference" "C4386"
			(at 0 0 0)
			(layer "B.SilkS")
			(hide yes)
			(effects
				(font
					(size 1.27 1.27)
				)
				(justify mirror)
			)
		)
		(property "Value" ""
			(at 0 0 0)
			(layer "B.Fab")
			(effects
				(font
					(size 1.27 1.27)
				)
				(justify mirror)
			)
		)
		(duplicate_pad_numbers_are_jumpers no)
		(fp_line
			(start -1.2954 -0.5842)
			(end -1.2954 0.5842)
			(stroke
				(width 0.1524)
				(type default)
			)
			(layer "B.SilkS")
		)
		(fp_line
			(start -1.2954 0.5842)
			(end 1.2954 0.5842)
			(stroke
				(width 0.1524)
				(type default)
			)
			(layer "B.SilkS")
		)
		(fp_line
			(start 1.2954 -0.5842)
			(end -1.2954 -0.5842)
			(stroke
				(width 0.1524)
				(type default)
			)
			(layer "B.SilkS")
		)
		(fp_line
			(start 1.2954 0.5842)
			(end 1.2954 -0.5842)
			(stroke
				(width 0.1524)
				(type default)
			)
			(layer "B.SilkS")
		)
		(fp_line
			(start -1.1938 -0.4064)
			(end -1.1938 0.4064)
			(stroke
				(width 0.1)
				(type default)
			)
			(layer "B.Fab")
		)
		(fp_line
			(start -1.1938 0.4064)
			(end -0.8636 0.4064)
			(stroke
				(width 0.1)
				(type default)
			)
			(layer "B.Fab")
		)
		(fp_line
			(start -0.8636 -0.4572)
			(end -0.8636 -0.4064)
			(stroke
				(width 0.1)
				(type default)
			)
			(layer "B.Fab")
		)
		(fp_line
			(start -0.8636 -0.4064)
			(end -1.1938 -0.4064)
			(stroke
				(width 0.1)
				(type default)
			)
			(layer "B.Fab")
		)
		(fp_line
			(start -0.8636 0.4064)
			(end -0.8636 0.4572)
			(stroke
				(width 0.1)
				(type default)
			)
			(layer "B.Fab")
		)
		(fp_line
			(start -0.8636 0.4572)
			(end 0.8636 0.4572)
			(stroke
				(width 0.1)
				(type default)
			)
			(layer "B.Fab")
		)
		(fp_line
			(start 0.8636 -0.4572)
			(end -0.8636 -0.4572)
			(stroke
				(width 0.1)
				(type default)
			)
			(layer "B.Fab")
		)
		(fp_line
			(start 0.8636 -0.4064)
			(end 0.8636 -0.4572)
			(stroke
				(width 0.1)
				(type default)
			)
			(layer "B.Fab")
		)
		(fp_line
			(start 0.8636 0.4064)
			(end 1.1938 0.4064)
			(stroke
				(width 0.1)
				(type default)
			)
			(layer "B.Fab")
		)
		(fp_line
			(start 0.8636 0.4572)
			(end 0.8636 0.4064)
			(stroke
				(width 0.1)
				(type default)
			)
			(layer "B.Fab")
		)
		(fp_line
			(start 1.1938 -0.4064)
			(end 0.8636 -0.4064)
			(stroke
				(width 0.1)
				(type default)
			)
			(layer "B.Fab")
		)
		(fp_line
			(start 1.1938 0.4064)
			(end 1.1938 -0.4064)
			(stroke
				(width 0.1)
				(type default)
			)
			(layer "B.Fab")
		)
		(pad "1" smd rect
			(at 0.7366 0 270)
			(size 0.7112 0.8128)
			(layers "B.Cu" "B.Mask" "B.Paste")
			(net "P1V25_PEX3")
		)
		(pad "2" smd rect
			(at -0.7366 0 270)
			(size 0.7112 0.8128)
			(layers "B.Cu" "B.Mask" "B.Paste")
			(net "GND")
		)
	)
	(footprint ""
		(layer "B.Cu")
		(at 454.797668 -277.176484 180)
		(property "Reference" "C4390"
			(at 0 0 0)
			(layer "B.SilkS")
			(hide yes)
			(effects
				(font
					(size 1.27 1.27)
				)
				(justify mirror)
			)
		)
		(property "Value" ""
			(at 0 0 0)
			(layer "B.Fab")
			(effects
				(font
					(size 1.27 1.27)
				)
				(justify mirror)
			)
		)
		(duplicate_pad_numbers_are_jumpers no)
		(fp_line
			(start 0.299974 0.150114)
			(end 0.299974 -0.150114)
			(stroke
				(width 0.1)
				(type default)
			)
			(layer "B.Fab")
		)
		(fp_line
			(start 0.299974 -0.150114)
			(end -0.299974 -0.150114)
			(stroke
				(width 0.1)
				(type default)
			)
			(layer "B.Fab")
		)
		(fp_line
			(start -0.299974 0.150114)
			(end 0.299974 0.150114)
			(stroke
				(width 0.1)
				(type default)
			)
			(layer "B.Fab")
		)
		(fp_line
			(start -0.299974 -0.150114)
			(end -0.299974 0.150114)
			(stroke
				(width 0.1)
				(type default)
			)
			(layer "B.Fab")
		)
		(pad "1" smd rect
			(at 0.2667 0)
			(size 0.3048 0.381)
			(layers "B.Cu" "B.Mask" "B.Paste")
			(net "P1V25_PEX3")
		)
		(pad "2" smd rect
			(at -0.2667 0)
			(size 0.3048 0.381)
			(layers "B.Cu" "B.Mask" "B.Paste")
			(net "GND")
		)
	)
	(footprint ""
		(layer "B.Cu")
		(at 49.67478 -293.99992 -90)
		(property "Reference" "C1137"
			(at 0 0 90)
			(layer "B.SilkS")
			(hide yes)
			(effects
				(font
					(size 1.27 1.27)
				)
				(justify mirror)
			)
		)
		(property "Value" ""
			(at 0 0 90)
			(layer "B.Fab")
			(effects
				(font
					(size 1.27 1.27)
				)
				(justify mirror)
			)
		)
		(duplicate_pad_numbers_are_jumpers no)
		(fp_line
			(start -0.299974 0.150114)
			(end 0.299974 0.150114)
			(stroke
				(width 0.1)
				(type default)
			)
			(layer "B.Fab")
		)
		(fp_line
			(start 0.299974 0.150114)
			(end 0.299974 -0.150114)
			(stroke
				(width 0.1)
				(type default)
			)
			(layer "B.Fab")
		)
		(fp_line
			(start -0.299974 -0.150114)
			(end -0.299974 0.150114)
			(stroke
				(width 0.1)
				(type default)
			)
			(layer "B.Fab")
		)
		(fp_line
			(start 0.299974 -0.150114)
			(end -0.299974 -0.150114)
			(stroke
				(width 0.1)
				(type default)
			)
			(layer "B.Fab")
		)
		(pad "1" smd rect
			(at 0.2667 0 90)
			(size 0.3048 0.381)
			(layers "B.Cu" "B.Mask" "B.Paste")
			(net "P0V8_PEX0")
		)
		(pad "2" smd rect
			(at -0.2667 0 90)
			(size 0.3048 0.381)
			(layers "B.Cu" "B.Mask" "B.Paste")
			(net "GND")
		)
	)
	(footprint ""
		(layer "B.Cu")
		(at 179.55006 -290.199826 90)
		(property "Reference" "C1458"
			(at 0 0 90)
			(layer "B.SilkS")
			(hide yes)
			(effects
				(font
					(size 1.27 1.27)
				)
				(justify mirror)
			)
		)
		(property "Value" ""
			(at 0 0 90)
			(layer "B.Fab")
			(effects
				(font
					(size 1.27 1.27)
				)
				(justify mirror)
			)
		)
		(duplicate_pad_numbers_are_jumpers no)
		(fp_line
			(start 0.299974 -0.150114)
			(end -0.299974 -0.150114)
			(stroke
				(width 0.1)
				(type default)
			)
			(layer "B.Fab")
		)
		(fp_line
			(start -0.299974 -0.150114)
			(end -0.299974 0.150114)
			(stroke
				(width 0.1)
				(type default)
			)
			(layer "B.Fab")
		)
		(fp_line
			(start 0.299974 0.150114)
			(end 0.299974 -0.150114)
			(stroke
				(width 0.1)
				(type default)
			)
			(layer "B.Fab")
		)
		(fp_line
			(start -0.299974 0.150114)
			(end 0.299974 0.150114)
			(stroke
				(width 0.1)
				(type default)
			)
			(layer "B.Fab")
		)
		(pad "1" smd rect
			(at 0.2667 0 270)
			(size 0.3048 0.381)
			(layers "B.Cu" "B.Mask" "B.Paste")
			(net "P0V8_SERDES_VDDA_PEX1")
		)
		(pad "2" smd rect
			(at -0.2667 0 270)
			(size 0.3048 0.381)
			(layers "B.Cu" "B.Mask" "B.Paste")
			(net "GND")
		)
	)
	(footprint ""
		(layer "B.Cu")
		(at 60.124848 -293.99992 -90)
		(property "Reference" "C1136"
			(at 0 0 90)
			(layer "B.SilkS")
			(hide yes)
			(effects
				(font
					(size 1.27 1.27)
				)
				(justify mirror)
			)
		)
		(property "Value" ""
			(at 0 0 90)
			(layer "B.Fab")
			(effects
				(font
					(size 1.27 1.27)
				)
				(justify mirror)
			)
		)
		(duplicate_pad_numbers_are_jumpers no)
		(fp_line
			(start -0.299974 0.150114)
			(end 0.299974 0.150114)
			(stroke
				(width 0.1)
				(type default)
			)
			(layer "B.Fab")
		)
		(fp_line
			(start 0.299974 0.150114)
			(end 0.299974 -0.150114)
			(stroke
				(width 0.1)
				(type default)
			)
			(layer "B.Fab")
		)
		(fp_line
			(start -0.299974 -0.150114)
			(end -0.299974 0.150114)
			(stroke
				(width 0.1)
				(type default)
			)
			(layer "B.Fab")
		)
		(fp_line
			(start 0.299974 -0.150114)
			(end -0.299974 -0.150114)
			(stroke
				(width 0.1)
				(type default)
			)
			(layer "B.Fab")
		)
		(pad "1" smd rect
			(at 0.2667 0 90)
			(size 0.3048 0.381)
			(layers "B.Cu" "B.Mask" "B.Paste")
			(net "P0V8_PEX0")
		)
		(pad "2" smd rect
			(at -0.2667 0 90)
			(size 0.3048 0.381)
			(layers "B.Cu" "B.Mask" "B.Paste")
			(net "GND")
		)
	)
	(footprint ""
		(layer "B.Cu")
		(at 386.890768 10.682732)
		(property "Reference" "DE16T_2"
			(at 2.542032 3.136138 0)
			(unlocked yes)
			(layer "B.SilkS")
			(effects
				(font
					(size 0.7874 0.5842)
					(thickness 0.1524)
				)
				(justify left mirror)
			)
		)
		(property "Value" ""
			(at 0 0 0)
			(layer "B.Fab")
			(effects
				(font
					(size 1.27 1.27)
				)
				(justify mirror)
			)
		)
		(duplicate_pad_numbers_are_jumpers no)
		(fp_line
			(start -1.2192 -2.1082)
			(end -1.2192 2.1082)
			(stroke
				(width 0.1524)
				(type default)
			)
			(layer "B.SilkS")
		)
		(fp_line
			(start -1.2192 2.1082)
			(end 1.2192 2.1082)
			(stroke
				(width 0.1524)
				(type default)
			)
			(layer "B.SilkS")
		)
		(fp_line
			(start 1.2192 -2.1082)
			(end -1.2192 -2.1082)
			(stroke
				(width 0.1524)
				(type default)
			)
			(layer "B.SilkS")
		)
		(fp_line
			(start 1.2192 2.1082)
			(end 1.2192 -2.1082)
			(stroke
				(width 0.1524)
				(type default)
			)
			(layer "B.SilkS")
		)
		(pad "" np_thru_hole circle
			(at -3.4671 -1.27 270)
			(size 1.0414 1.0414)
			(drill 1.0414)
			(layers "*.Cu" "*.Mask")
			(clearance 0.381)
			(thermal_gap 0.381)
		)
		(pad "" np_thru_hole circle
			(at -3.4671 1.27 270)
			(size 1.0414 1.0414)
			(drill 1.0414)
			(layers "*.Cu" "*.Mask")
			(clearance 0.381)
			(thermal_gap 0.381)
		)
		(pad "" np_thru_hole circle
			(at 2.8829 -1.27 270)
			(size 1.0414 1.0414)
			(drill 1.0414)
			(layers "*.Cu" "*.Mask")
			(clearance 0.381)
			(thermal_gap 0.381)
		)
		(pad "" np_thru_hole circle
			(at 2.8829 1.27 270)
			(size 1.0414 1.0414)
			(drill 1.0414)
			(layers "*.Cu" "*.Mask")
			(clearance 0.381)
			(thermal_gap 0.381)
		)
		(pad "1" smd rect
			(at -0.8255 -0.249936 270)
			(size 0.3048 0.508)
			(layers "B.Cu" "B.Mask" "B.Paste")
			(net "85_10INCH_IN4_DN")
		)
		(pad "2" smd rect
			(at -0.8255 0.249936 270)
			(size 0.3048 0.508)
			(layers "B.Cu" "B.Mask" "B.Paste")
			(net "85_10INCH_IN4_DP")
		)
		(pad "3" smd circle
			(at 0 0 180)
			(size 0 0)
			(layers "B.Cu" "B.Mask" "B.Paste")
			(net "COUPON_GND2")
		)
		(zone
			(layers "F.Cu" "B.Cu" "In1.Cu" "In2.Cu" "In3.Cu" "In4.Cu" "In5.Cu" "In6.Cu"
				"In7.Cu" "In8.Cu" "In9.Cu" "In10.Cu" "In11.Cu" "In12.Cu" "In13.Cu" "In14.Cu"
				"In15.Cu" "In16.Cu"
			)
			(hatch none 0.5)
			(connect_pads
				(clearance 0)
			)
			(min_thickness 0.25)
			(keepout
				(tracks not_allowed)
				(vias allowed)
				(pads allowed)
				(copperpour not_allowed)
				(footprints allowed)
			)
			(placement
				(enabled no)
				(sheetname "")
			)
			(fill
				(thermal_gap 0.5)
				(thermal_bridge_width 0.5)
				(island_removal_mode 0)
			)
			(polygon
				(pts
					(arc
						(start 384.350768 9.412732)
						(mid 382.496568 9.412732)
						(end 384.350768 9.412732)
					)
				)
			)
		)
		(zone
			(layers "F.Cu" "B.Cu" "In1.Cu" "In2.Cu" "In3.Cu" "In4.Cu" "In5.Cu" "In6.Cu"
				"In7.Cu" "In8.Cu" "In9.Cu" "In10.Cu" "In11.Cu" "In12.Cu" "In13.Cu" "In14.Cu"
				"In15.Cu" "In16.Cu"
			)
			(hatch none 0.5)
			(connect_pads
				(clearance 0)
			)
			(min_thickness 0.25)
			(keepout
				(tracks not_allowed)
				(vias allowed)
				(pads allowed)
				(copperpour not_allowed)
				(footprints allowed)
			)
			(placement
				(enabled no)
				(sheetname "")
			)
			(fill
				(thermal_gap 0.5)
				(thermal_bridge_width 0.5)
				(island_removal_mode 0)
			)
			(polygon
				(pts
					(arc
						(start 384.350768 11.952732)
						(mid 382.496568 11.952732)
						(end 384.350768 11.952732)
					)
				)
			)
		)
		(zone
			(layers "F.Cu" "B.Cu" "In1.Cu" "In2.Cu" "In3.Cu" "In4.Cu" "In5.Cu" "In6.Cu"
				"In7.Cu" "In8.Cu" "In9.Cu" "In10.Cu" "In11.Cu" "In12.Cu" "In13.Cu" "In14.Cu"
				"In15.Cu" "In16.Cu"
			)
			(hatch none 0.5)
			(connect_pads
				(clearance 0)
			)
			(min_thickness 0.25)
			(keepout
				(tracks not_allowed)
				(vias allowed)
				(pads allowed)
				(copperpour not_allowed)
				(footprints allowed)
			)
			(placement
				(enabled no)
				(sheetname "")
			)
			(fill
				(thermal_gap 0.5)
				(thermal_bridge_width 0.5)
				(island_removal_mode 0)
			)
			(polygon
				(pts
					(arc
						(start 390.700768 9.412732)
						(mid 388.846568 9.412732)
						(end 390.700768 9.412732)
					)
				)
			)
		)
		(zone
			(layers "F.Cu" "B.Cu" "In1.Cu" "In2.Cu" "In3.Cu" "In4.Cu" "In5.Cu" "In6.Cu"
				"In7.Cu" "In8.Cu" "In9.Cu" "In10.Cu" "In11.Cu" "In12.Cu" "In13.Cu" "In14.Cu"
				"In15.Cu" "In16.Cu"
			)
			(hatch none 0.5)
			(connect_pads
				(clearance 0)
			)
			(min_thickness 0.25)
			(keepout
				(tracks not_allowed)
				(vias allowed)
				(pads allowed)
				(copperpour not_allowed)
				(footprints allowed)
			)
			(placement
				(enabled no)
				(sheetname "")
			)
			(fill
				(thermal_gap 0.5)
				(thermal_bridge_width 0.5)
				(island_removal_mode 0)
			)
			(polygon
				(pts
					(arc
						(start 390.700768 11.952732)
						(mid 388.846568 11.952732)
						(end 390.700768 11.952732)
					)
				)
			)
		)
		(zone
			(layer "B.Cu")
			(hatch none 0.5)
			(connect_pads
				(clearance 0)
			)
			(min_thickness 0.25)
			(keepout
				(tracks not_allowed)
				(vias allowed)
				(pads allowed)
				(copperpour not_allowed)
				(footprints allowed)
			)
			(placement
				(enabled no)
				(sheetname "")
			)
			(fill
				(thermal_gap 0.5)
				(thermal_bridge_width 0.5)
				(island_removal_mode 0)
			)
			(polygon
				(pts
					(xy 385.773168 10.134092) (xy 385.773168 10.229596) (xy 386.370068 10.229596) (xy 386.370068 10.635996)
					(xy 385.773168 10.635996) (xy 385.773168 10.729468) (xy 386.370068 10.729468) (xy 386.370068 11.135868)
					(xy 385.773168 11.135868) (xy 385.773168 11.231372) (xy 386.471668 11.231372) (xy 386.471668 10.134092)
				)
			)
		)
	)
	(footprint ""
		(layer "B.Cu")
		(at 135.697214 -209.333846 90)
		(property "Reference" "C2593"
			(at 0 0 90)
			(layer "B.SilkS")
			(hide yes)
			(effects
				(font
					(size 1.27 1.27)
				)
				(justify mirror)
			)
		)
		(property "Value" ""
			(at 0 0 90)
			(layer "B.Fab")
			(effects
				(font
					(size 1.27 1.27)
				)
				(justify mirror)
			)
		)
		(duplicate_pad_numbers_are_jumpers no)
		(fp_line
			(start 0.7874 -0.4064)
			(end -0.7874 -0.4064)
			(stroke
				(width 0.1524)
				(type default)
			)
			(layer "B.SilkS")
		)
		(fp_line
			(start -0.7874 -0.4064)
			(end -0.7874 0.4064)
			(stroke
				(width 0.1524)
				(type default)
			)
			(layer "B.SilkS")
		)
		(fp_line
			(start 0.7874 0.4064)
			(end 0.7874 -0.4064)
			(stroke
				(width 0.1524)
				(type default)
			)
			(layer "B.SilkS")
		)
		(fp_line
			(start -0.7874 0.4064)
			(end 0.7874 0.4064)
			(stroke
				(width 0.1524)
				(type default)
			)
			(layer "B.SilkS")
		)
		(fp_line
			(start 0.67945 -0.305054)
			(end 0.12065 -0.305054)
			(stroke
				(width 0.1)
				(type default)
			)
			(layer "B.Fab")
		)
		(fp_line
			(start 0.12065 -0.305054)
			(end 0.12065 -0.2794)
			(stroke
				(width 0.1)
				(type default)
			)
			(layer "B.Fab")
		)
		(fp_line
			(start -0.12065 -0.3048)
			(end -0.67945 -0.3048)
			(stroke
				(width 0.1)
				(type default)
			)
			(layer "B.Fab")
		)
		(fp_line
			(start -0.67945 -0.3048)
			(end -0.67945 0.3048)
			(stroke
				(width 0.1)
				(type default)
			)
			(layer "B.Fab")
		)
		(fp_line
			(start 0.12065 -0.2794)
			(end -0.12065 -0.2794)
			(stroke
				(width 0.1)
				(type default)
			)
			(layer "B.Fab")
		)
		(fp_line
			(start -0.12065 -0.2794)
			(end -0.12065 -0.3048)
			(stroke
				(width 0.1)
				(type default)
			)
			(layer "B.Fab")
		)
		(fp_line
			(start 0.12065 0.2794)
			(end 0.12065 0.3048)
			(stroke
				(width 0.1)
				(type default)
			)
			(layer "B.Fab")
		)
		(fp_line
			(start -0.120396 0.2794)
			(end 0.12065 0.2794)
			(stroke
				(width 0.1)
				(type default)
			)
			(layer "B.Fab")
		)
		(fp_line
			(start 0.67945 0.3048)
			(end 0.67945 -0.305054)
			(stroke
				(width 0.1)
				(type default)
			)
			(layer "B.Fab")
		)
		(fp_line
			(start 0.12065 0.3048)
			(end 0.67945 0.3048)
			(stroke
				(width 0.1)
				(type default)
			)
			(layer "B.Fab")
		)
		(fp_line
			(start -0.120396 0.3048)
			(end -0.120396 0.2794)
			(stroke
				(width 0.1)
				(type default)
			)
			(layer "B.Fab")
		)
		(fp_line
			(start -0.67945 0.3048)
			(end -0.120396 0.3048)
			(stroke
				(width 0.1)
				(type default)
			)
			(layer "B.Fab")
		)
		(pad "1" smd circle
			(at 0.40005 0 270)
			(size 0 0)
			(layers "B.Cu" "B.Mask" "B.Paste")
			(net "P1V8_CLI_VCORE")
		)
		(pad "2" smd circle
			(at -0.40005 0 270)
			(size 0 0)
			(layers "B.Cu" "B.Mask" "B.Paste")
			(net "GND")
		)
	)
)
